# BASEBOARD_FAB2 (Tioga Pass) — schematic netlist excerpt (pin names and nets, part order shuffled) for the footprints in the layout excerpt that follows; sources: Cadence DE-HDL packaged netlist, KiCad conversion of Wiwynn_Tioga_Pass_MB.brd

C6N4  CAPP  470UF 2.5V 20% ALUM  pkg 3018  page 205 : A = PVSA_CPU0 ; B = GND
C8F4  CAP_A  1.0UF 6.3V 10% X6S  pkg 0402V  page 162 : A = P3V3_STBY ; B = GND
R5P2  RES  49.9 1% CHIP  pkg 0402  page 90 : A = PD_CPU0_TEST14 ; B = GND

(kicad_pcb
	(version 20260206)
	(generator "pcbnew")
	(generator_version "10.0")
	(general
		(thickness 1.6)
		(legacy_teardrops no)
	)
	(paper "A4")
	(title_block
		(title "Wiwynn_Tioga_Pass_MB.brd")
		(comment 1 "Tioga Pass / footprints 4515-4517 of 4770")
	)
	(layers
		(0 "F.Cu" signal "TOP")
		(4 "In1.Cu" signal "L2GND")
		(6 "In2.Cu" signal "L3")
		(8 "In3.Cu" signal "L4GND")
		(10 "In4.Cu" signal "L5")
		(12 "In5.Cu" signal "L6GND")
		(14 "In6.Cu" signal "L7VCC")
		(16 "In7.Cu" signal "L8VCC")
		(18 "In8.Cu" signal "L9GND")
		(20 "In9.Cu" signal "L10")
		(22 "In10.Cu" signal "L11GND")
		(24 "In11.Cu" signal "L12")
		(26 "In12.Cu" signal "L13GND")
		(2 "B.Cu" signal "BOTTOM")
		(9 "F.Adhes" user "F.Adhesive")
		(11 "B.Adhes" user "B.Adhesive")
		(13 "F.Paste" user "Package Geometry/Pastemask Top")
		(15 "B.Paste" user "Package Geometry/Pastemask Bottom")
		(5 "F.SilkS" user "Ref Des/Silkscreen Top")
		(7 "B.SilkS" user "Ref Des/Silkscreen Bottom")
		(1 "F.Mask" user "Board Geometry/Soldermask Top")
		(3 "B.Mask" user "Board Geometry/Soldermask Bottom")
		(17 "Dwgs.User" user "User.Drawings")
		(19 "Cmts.User" user "User.Comments")
		(21 "Eco1.User" user "User.Eco1")
		(23 "Eco2.User" user "User.Eco2")
		(25 "Edge.Cuts" user "Board Geometry/Outline")
		(27 "Margin" user)
		(31 "F.CrtYd" user "Package Geometry/Place Bound Top")
		(29 "B.CrtYd" user "Package Geometry/Place Bound Bottom")
		(35 "F.Fab" user "Ref Des/Assembly Top")
		(33 "B.Fab" user "Ref Des/Assembly Bottom")
	)
	(footprint ""
		(layer "B.Cu")
		(at 365.379 -40.5892 180)
		(property "Reference" "C8F4"
			(at 0 0 0)
			(layer "B.SilkS")
			(hide yes)
			(effects
				(font
					(size 1.27 1.27)
				)
				(justify mirror)
			)
		)
		(property "Value" ""
			(at 0 0 0)
			(layer "B.Fab")
			(effects
				(font
					(size 1.27 1.27)
				)
				(justify mirror)
			)
		)
		(duplicate_pad_numbers_are_jumpers no)
		(fp_poly
			(pts
				(xy -0.3048 -0.1016) (xy -0.3048 0.9906) (xy 0.3048 0.9906) (xy 0.3048 -0.1016)
			)
			(stroke
				(width 0)
				(type default)
			)
			(fill no)
			(layer "B.CrtYd")
		)
		(fp_line
			(start 0.3048 0.9906)
			(end -0.3048 0.9906)
			(stroke
				(width 0.1)
				(type default)
			)
			(layer "B.Fab")
		)
		(fp_line
			(start 0.3048 -0.1016)
			(end 0.3048 0.9906)
			(stroke
				(width 0.1)
				(type default)
			)
			(layer "B.Fab")
		)
		(fp_line
			(start -0.3048 0.9906)
			(end -0.3048 -0.1016)
			(stroke
				(width 0.1)
				(type default)
			)
			(layer "B.Fab")
		)
		(fp_line
			(start -0.3048 -0.1016)
			(end 0.3048 -0.1016)
			(stroke
				(width 0.1)
				(type default)
			)
			(layer "B.Fab")
		)
		(pad "1" smd rect
			(at 0 0)
			(size 0.508 0.508)
			(layers "B.Cu" "B.Mask" "B.Paste")
			(net "P3V3_STBY")
		)
		(pad "2" smd rect
			(at 0 0.889)
			(size 0.508 0.508)
			(layers "B.Cu" "B.Mask" "B.Paste")
			(net "GND")
		)
		(zone
			(layer "B.Cu")
			(hatch none 0.5)
			(connect_pads
				(clearance 0)
			)
			(min_thickness 0.25)
			(keepout
				(tracks not_allowed)
				(vias allowed)
				(pads allowed)
				(copperpour not_allowed)
				(footprints allowed)
			)
			(placement
				(enabled no)
				(sheetname "")
			)
			(fill
				(thermal_gap 0.5)
				(thermal_bridge_width 0.5)
				(island_removal_mode 0)
			)
			(polygon
				(pts
					(xy 365.125 -41.2242) (xy 365.633 -41.2242) (xy 365.633 -40.8432) (xy 365.125 -40.8432)
				)
			)
		)
		(zone
			(layer "B.Cu")
			(hatch none 0.5)
			(connect_pads
				(clearance 0)
			)
			(min_thickness 0.25)
			(keepout
				(tracks allowed)
				(vias not_allowed)
				(pads allowed)
				(copperpour not_allowed)
				(footprints allowed)
			)
			(placement
				(enabled no)
				(sheetname "")
			)
			(fill
				(thermal_gap 0.5)
				(thermal_bridge_width 0.5)
				(island_removal_mode 0)
			)
			(polygon
				(pts
					(xy 365.125 -40.8432) (xy 365.633 -40.8432) (xy 365.633 -41.2242) (xy 365.125 -41.2242)
				)
			)
		)
	)
	(footprint ""
		(layer "B.Cu")
		(at 210.612228 -95.596202 -90)
		(property "Reference" "C6N4"
			(at -3.401568 -4.525772 0)
			(unlocked yes)
			(layer "B.SilkS")
			(effects
				(font
					(size 0.7874 0.5842)
					(thickness 0.1524)
				)
				(justify mirror)
			)
		)
		(property "Value" ""
			(at 0 0 90)
			(layer "B.Fab")
			(effects
				(font
					(size 1.27 1.27)
				)
				(justify mirror)
			)
		)
		(duplicate_pad_numbers_are_jumpers no)
		(fp_line
			(start -2.286 7.366)
			(end -1.600708 7.366)
			(stroke
				(width 0.1524)
				(type default)
			)
			(layer "B.SilkS")
		)
		(fp_line
			(start -2.286 7.366)
			(end -2.286 1.63195)
			(stroke
				(width 0.1524)
				(type default)
			)
			(layer "B.SilkS")
		)
		(fp_line
			(start 2.286 7.366)
			(end 1.60147 7.366)
			(stroke
				(width 0.1524)
				(type default)
			)
			(layer "B.SilkS")
		)
		(fp_line
			(start 2.286 7.366)
			(end 2.286 1.632712)
			(stroke
				(width 0.1524)
				(type default)
			)
			(layer "B.SilkS")
		)
		(fp_line
			(start -2.504948 1.633728)
			(end -1.6002 1.633728)
			(stroke
				(width 0.1524)
				(type default)
			)
			(layer "B.SilkS")
		)
		(fp_line
			(start 2.563114 1.633728)
			(end 1.6002 1.633728)
			(stroke
				(width 0.1524)
				(type default)
			)
			(layer "B.SilkS")
		)
		(fp_line
			(start -2.504948 -1.616456)
			(end -2.504948 1.633728)
			(stroke
				(width 0.1524)
				(type default)
			)
			(layer "B.SilkS")
		)
		(fp_line
			(start -1.6002 -1.616456)
			(end -2.504948 -1.616456)
			(stroke
				(width 0.1524)
				(type default)
			)
			(layer "B.SilkS")
		)
		(fp_line
			(start 1.6002 -1.616456)
			(end 2.563114 -1.616456)
			(stroke
				(width 0.1524)
				(type default)
			)
			(layer "B.SilkS")
		)
		(fp_line
			(start 2.563114 -1.616456)
			(end 2.563114 1.633728)
			(stroke
				(width 0.1524)
				(type default)
			)
			(layer "B.SilkS")
		)
		(fp_rect
			(start 2.286 7.366)
			(end -2.286 -0.254)
			(stroke
				(width 0)
				(type default)
			)
			(fill no)
			(layer "B.CrtYd")
		)
		(fp_line
			(start -2.286 7.366)
			(end 2.286 7.366)
			(stroke
				(width 0.1)
				(type default)
			)
			(layer "B.Fab")
		)
		(fp_line
			(start 2.286 7.366)
			(end 2.286 -0.254)
			(stroke
				(width 0.1)
				(type default)
			)
			(layer "B.Fab")
		)
		(fp_line
			(start -2.286 -0.254)
			(end -2.286 7.366)
			(stroke
				(width 0.1)
				(type default)
			)
			(layer "B.Fab")
		)
		(fp_line
			(start 2.286 -0.254)
			(end -2.286 -0.254)
			(stroke
				(width 0.1)
				(type default)
			)
			(layer "B.Fab")
		)
		(pad "1" smd rect
			(at 0 0 90)
			(size 2.54 3.048)
			(layers "B.Cu" "B.Mask" "B.Paste")
			(net "PVSA_CPU0")
		)
		(pad "2" smd rect
			(at 0 7.112 90)
			(size 2.54 3.048)
			(layers "B.Cu" "B.Mask" "B.Paste")
			(net "GND")
		)
	)
	(footprint ""
		(layer "B.Cu")
		(at 245.14302 -87.46236 -90)
		(property "Reference" "R5P2"
			(at 0 0 90)
			(layer "B.SilkS")
			(hide yes)
			(effects
				(font
					(size 1.27 1.27)
				)
				(justify mirror)
			)
		)
		(property "Value" ""
			(at 0 0 90)
			(layer "B.Fab")
			(effects
				(font
					(size 1.27 1.27)
				)
				(justify mirror)
			)
		)
		(duplicate_pad_numbers_are_jumpers no)
		(fp_poly
			(pts
				(xy 0.2794 -0.1016) (xy -0.2794 -0.1016) (xy -0.2794 0.9906) (xy 0.2794 0.9906)
			)
			(stroke
				(width 0)
				(type default)
			)
			(fill no)
			(layer "B.CrtYd")
		)
		(fp_line
			(start -0.2794 0.9906)
			(end -0.2794 -0.1016)
			(stroke
				(width 0.1)
				(type default)
			)
			(layer "B.Fab")
		)
		(fp_line
			(start 0.2794 0.9906)
			(end -0.2794 0.9906)
			(stroke
				(width 0.1)
				(type default)
			)
			(layer "B.Fab")
		)
		(fp_line
			(start -0.2794 -0.1016)
			(end 0.2794 -0.1016)
			(stroke
				(width 0.1)
				(type default)
			)
			(layer "B.Fab")
		)
		(fp_line
			(start 0.2794 -0.1016)
			(end 0.2794 0.9906)
			(stroke
				(width 0.1)
				(type default)
			)
			(layer "B.Fab")
		)
		(pad "1" smd rect
			(at 0 0 90)
			(size 0.508 0.508)
			(layers "B.Cu" "B.Mask" "B.Paste")
			(net "PD_CPU0_TEST14")
		)
		(pad "2" smd rect
			(at 0 0.889 90)
			(size 0.508 0.508)
			(layers "B.Cu" "B.Mask" "B.Paste")
			(net "GND")
		)
		(zone
			(layer "B.Cu")
			(hatch none 0.5)
			(connect_pads
				(clearance 0)
			)
			(min_thickness 0.25)
			(keepout
				(tracks not_allowed)
				(vias allowed)
				(pads allowed)
				(copperpour not_allowed)
				(footprints allowed)
			)
			(placement
				(enabled no)
				(sheetname "")
			)
			(fill
				(thermal_gap 0.5)
				(thermal_bridge_width 0.5)
				(island_removal_mode 0)
			)
			(polygon
				(pts
					(xy 244.50802 -87.20836) (xy 244.50802 -87.71636) (xy 244.88902 -87.71636) (xy 244.88902 -87.20836)
				)
			)
		)
		(zone
			(layer "B.Cu")
			(hatch none 0.5)
			(connect_pads
				(clearance 0)
			)
			(min_thickness 0.25)
			(keepout
				(tracks allowed)
				(vias not_allowed)
				(pads allowed)
				(copperpour not_allowed)
				(footprints allowed)
			)
			(placement
				(enabled no)
				(sheetname "")
			)
			(fill
				(thermal_gap 0.5)
				(thermal_bridge_width 0.5)
				(island_removal_mode 0)
			)
			(polygon
				(pts
					(xy 244.88902 -87.20836) (xy 244.88902 -87.71636) (xy 244.50802 -87.71636) (xy 244.50802 -87.20836)
				)
			)
		)
	)
)
